# T6G (Grand Teton) — schematic netlist excerpt (pin names and nets, part order shuffled) for the footprints in the layout excerpt that follows; sources: Cadence DE-HDL packaged netlist, KiCad conversion of 04192023_DAF0TMB3IC0_F0TG_MB_C_brd_V02_OCP.brd

C799  Q_CAP  22UF 4V 20% X6S  pkg C0402  page 301 : A = P0V9_CPU0_RT2_2A ; B = GND
C154  Q_CAP  10UF 25V 10% X6S  pkg C0805  page 91 : A = P12V_MEM_CPU0 ; B = GND

(kicad_pcb
	(version 20260206)
	(generator "pcbnew")
	(generator_version "10.0")
	(general
		(thickness 1.6)
		(legacy_teardrops no)
	)
	(paper "A4")
	(title_block
		(title "04192023_DAF0TMB3IC0_F0TG_MB_C_brd_V02_OCP.brd")
		(comment 1 "Grand Teton / footprints 7401-7402 of 8354")
	)
	(layers
		(0 "F.Cu" signal "TOP")
		(4 "In1.Cu" signal "GND")
		(6 "In2.Cu" signal "IN1")
		(8 "In3.Cu" signal "GND1")
		(10 "In4.Cu" signal "IN2")
		(12 "In5.Cu" signal "GND2")
		(14 "In6.Cu" signal "IN3")
		(16 "In7.Cu" signal "GND3")
		(18 "In8.Cu" signal "VCC")
		(20 "In9.Cu" signal "VCC1")
		(22 "In10.Cu" signal "GND4")
		(24 "In11.Cu" signal "IN4")
		(26 "In12.Cu" signal "GND5")
		(28 "In13.Cu" signal "IN5")
		(30 "In14.Cu" signal "GND6")
		(32 "In15.Cu" signal "IN6")
		(34 "In16.Cu" signal "GND7")
		(2 "B.Cu" signal "BOTTOM")
		(9 "F.Adhes" user "F.Adhesive")
		(11 "B.Adhes" user "B.Adhesive")
		(13 "F.Paste" user "Package Geometry/Pastemask Top")
		(15 "B.Paste" user "Package Geometry/Pastemask Bottom")
		(5 "F.SilkS" user "Ref Des/Silkscreen Top")
		(7 "B.SilkS" user "Ref Des/Silkscreen Bottom")
		(1 "F.Mask" user "Board Geometry/Soldermask Top")
		(3 "B.Mask" user "Board Geometry/Soldermask Bottom")
		(17 "Dwgs.User" user "User.Drawings")
		(19 "Cmts.User" user "User.Comments")
		(21 "Eco1.User" user "User.Eco1")
		(23 "Eco2.User" user "User.Eco2")
		(25 "Edge.Cuts" user "Board Geometry/Outline")
		(27 "Margin" user)
		(31 "F.CrtYd" user "Package Geometry/Place Bound Top")
		(29 "B.CrtYd" user "Package Geometry/Place Bound Bottom")
		(35 "F.Fab" user "Ref Des/Assembly Top")
		(33 "B.Fab" user "Ref Des/Assembly Bottom")
	)
	(footprint ""
		(layer "B.Cu")
		(at 269.648178 -192.660016)
		(property "Reference" "C154"
			(at 0 0 0)
			(layer "B.SilkS")
			(hide yes)
			(effects
				(font
					(size 1.27 1.27)
				)
				(justify mirror)
			)
		)
		(property "Value" ""
			(at 0 0 0)
			(layer "B.Fab")
			(effects
				(font
					(size 1.27 1.27)
				)
				(justify mirror)
			)
		)
		(duplicate_pad_numbers_are_jumpers no)
		(fp_line
			(start -1.524 -0.762)
			(end -1.524 0.762)
			(stroke
				(width 0.1524)
				(type default)
			)
			(layer "B.SilkS")
		)
		(fp_line
			(start -1.524 0.762)
			(end 1.524 0.762)
			(stroke
				(width 0.1524)
				(type default)
			)
			(layer "B.SilkS")
		)
		(fp_line
			(start 1.524 -0.762)
			(end -1.524 -0.762)
			(stroke
				(width 0.1524)
				(type default)
			)
			(layer "B.SilkS")
		)
		(fp_line
			(start 1.524 0.762)
			(end 1.524 -0.762)
			(stroke
				(width 0.1524)
				(type default)
			)
			(layer "B.SilkS")
		)
		(fp_line
			(start -1.1049 -0.724916)
			(end 1.1049 -0.724916)
			(stroke
				(width 0.1)
				(type default)
			)
			(layer "B.Fab")
		)
		(fp_line
			(start -1.1049 0.724916)
			(end -1.1049 -0.724916)
			(stroke
				(width 0.1)
				(type default)
			)
			(layer "B.Fab")
		)
		(fp_line
			(start 1.1049 -0.724916)
			(end 1.1049 0.724916)
			(stroke
				(width 0.1)
				(type default)
			)
			(layer "B.Fab")
		)
		(fp_line
			(start 1.1049 0.724916)
			(end -1.1049 0.724916)
			(stroke
				(width 0.1)
				(type default)
			)
			(layer "B.Fab")
		)
		(pad "1" smd rect
			(at 0.889 0)
			(size 1.016 1.27)
			(layers "B.Cu" "B.Mask" "B.Paste")
			(net "P12V_MEM_CPU0")
		)
		(pad "2" smd rect
			(at -0.889 0)
			(size 1.016 1.27)
			(layers "B.Cu" "B.Mask" "B.Paste")
			(net "GND")
		)
	)
	(footprint ""
		(layer "B.Cu")
		(at 407.819098 -398.942052 90)
		(property "Reference" "C799"
			(at 0 0 90)
			(layer "B.SilkS")
			(hide yes)
			(effects
				(font
					(size 1.27 1.27)
				)
				(justify mirror)
			)
		)
		(property "Value" ""
			(at 0 0 90)
			(layer "B.Fab")
			(effects
				(font
					(size 1.27 1.27)
				)
				(justify mirror)
			)
		)
		(duplicate_pad_numbers_are_jumpers no)
		(fp_line
			(start 0.7874 -0.4064)
			(end -0.7874 -0.4064)
			(stroke
				(width 0.1524)
				(type default)
			)
			(layer "B.SilkS")
		)
		(fp_line
			(start -0.7874 -0.4064)
			(end -0.7874 0.4064)
			(stroke
				(width 0.1524)
				(type default)
			)
			(layer "B.SilkS")
		)
		(fp_line
			(start 0.7874 0.4064)
			(end 0.7874 -0.4064)
			(stroke
				(width 0.1524)
				(type default)
			)
			(layer "B.SilkS")
		)
		(fp_line
			(start -0.7874 0.4064)
			(end 0.7874 0.4064)
			(stroke
				(width 0.1524)
				(type default)
			)
			(layer "B.SilkS")
		)
		(fp_line
			(start 0.67945 -0.305054)
			(end 0.12065 -0.305054)
			(stroke
				(width 0.1)
				(type default)
			)
			(layer "B.Fab")
		)
		(fp_line
			(start 0.12065 -0.305054)
			(end 0.12065 -0.2794)
			(stroke
				(width 0.1)
				(type default)
			)
			(layer "B.Fab")
		)
		(fp_line
			(start -0.12065 -0.3048)
			(end -0.67945 -0.3048)
			(stroke
				(width 0.1)
				(type default)
			)
			(layer "B.Fab")
		)
		(fp_line
			(start -0.67945 -0.3048)
			(end -0.67945 0.3048)
			(stroke
				(width 0.1)
				(type default)
			)
			(layer "B.Fab")
		)
		(fp_line
			(start 0.12065 -0.2794)
			(end -0.12065 -0.2794)
			(stroke
				(width 0.1)
				(type default)
			)
			(layer "B.Fab")
		)
		(fp_line
			(start -0.12065 -0.2794)
			(end -0.12065 -0.3048)
			(stroke
				(width 0.1)
				(type default)
			)
			(layer "B.Fab")
		)
		(fp_line
			(start 0.12065 0.2794)
			(end 0.12065 0.3048)
			(stroke
				(width 0.1)
				(type default)
			)
			(layer "B.Fab")
		)
		(fp_line
			(start -0.120396 0.2794)
			(end 0.12065 0.2794)
			(stroke
				(width 0.1)
				(type default)
			)
			(layer "B.Fab")
		)
		(fp_line
			(start 0.67945 0.3048)
			(end 0.67945 -0.305054)
			(stroke
				(width 0.1)
				(type default)
			)
			(layer "B.Fab")
		)
		(fp_line
			(start 0.12065 0.3048)
			(end 0.67945 0.3048)
			(stroke
				(width 0.1)
				(type default)
			)
			(layer "B.Fab")
		)
		(fp_line
			(start -0.120396 0.3048)
			(end -0.120396 0.2794)
			(stroke
				(width 0.1)
				(type default)
			)
			(layer "B.Fab")
		)
		(fp_line
			(start -0.67945 0.3048)
			(end -0.120396 0.3048)
			(stroke
				(width 0.1)
				(type default)
			)
			(layer "B.Fab")
		)
		(pad "1" smd circle
			(at 0.40005 0 270)
			(size 0 0)
			(layers "B.Cu" "B.Mask" "B.Paste")
			(net "P0V9_CPU0_RT2_2A")
		)
		(pad "2" smd circle
			(at -0.40005 0 270)
			(size 0 0)
			(layers "B.Cu" "B.Mask" "B.Paste")
			(net "GND")
		)
	)
)
